# S9S_MB_2U (Grand Teton) — schematic parts with pin connectivity, parts 1756–1908 of 6093; source: Cadence DE-HDL packaged netlist (pstxprt.dat, pstxnet.dat, pstchip.dat)

PC197_P0_1  Q_CAP  22UF 16V 20% X6S  pkg C0805  page 275 : 1 = SW_P12V_PVCCINFAON_CPU0_FLT ; 2 = GND
PC198_P0_2  Q_CAP  22UF 16V 20% X6S  pkg C0805  page 275 : 1 = SW_P12V_PVCCINFAON_CPU0_FLT ; 2 = GND
PC199_P0_1  Q_CAP  100NF 50V 10% X7R  pkg C0402  page 275 : 1 = PVCCINFAON_CPU0 ; 2 = GND
PC202_P0_1  Q_CAP  22UF 4V 20% X6S  pkg C0805  page 275 : 1 = PVCCINFAON_CPU0 ; 2 = GND
PC203_P0_2  Q_CAP  22UF 4V 20% X6S  pkg C0805  page 275 : 1 = PVCCINFAON_CPU0 ; 2 = GND
PC204_P0_1  Q_CAP  22UF 4V 20% X6S  pkg C0805  page 275 : 1 = PVCCINFAON_CPU0 ; 2 = GND
PC205_P0_2  Q_CAP  22UF 4V 20% X6S  pkg C0805  page 275 : 1 = PVCCINFAON_CPU0 ; 2 = GND
PC207  Q_CAPP  270UF 16V 20% OSCON  pkg THLF  page 275 : 1 = SW_P12V_PVCCINFAON_CPU0_FLT ; 2 = GND
PC208  Q_CAPP  270UF 16V 20% OSCON  pkg THLF  page 275 : 1 = SW_P12V_PVCCINFAON_CPU0_FLT ; 2 = GND
PC214  Q_CAP  0.1UF 25V 10% EMPTY  pkg 0402  page 274 : 1 = PVCCINFAON_CPU0_CSPIN ; 2 = GND
PC215  Q_CAP  3300PF 50V 10% X7R  pkg 0402  page 274 : 1 = SH_PVCCINFAON_CPU0_R ; 2 = VSENSE_PVCCINFAON_CPU0_DN
PC216  Q_CAP  3300PF 50V 10% X7R  pkg 0402  page 274 : 1 = SH_PVCCFA_EHV_CPU0_R ; 2 = VSENSE_PVCCFA_EHV_CPU0_DN
PC221  Q_CAP  0.1UF 25V 10% X7R  pkg 0402  page 274 : 1 = PVCCINFAON_CPU0_VIN_CSNIN ; 2 = GND
PC222  Q_CAP  470PF 50V 10% X7R  pkg 0402  page 274 : 1 = PVCCINFAON_CPU0_ATSEN ; 2 = GND
PC223  Q_CAP  100NF 50V 10% EMPTY  pkg C0402  page 274 : 1 = PVCCINFAON_CPU0_VCC ; 2 = GND
PC224  Q_CAP  10UF 6.3V 20% X6S  pkg C0402  page 274 : 1 = PVCCINFAON_CPU0_VREF ; 2 = GND
PC225  Q_CAP  1UF 16V 10% X6S  pkg C0402  page 274 : 1 = PVCCINFAON_CPU0_VCC ; 2 = GND
PC226  Q_CAP  2.2UF 10V 10% X6S  pkg C0402  page 270 : 1 = PVCCIN_CPU0_VDD8 ; 2 = GND
PC227  Q_CAP  2.2UF 10V 10% X6S  pkg C0402  page 270 : 1 = PVCCIN_CPU0_VDD7 ; 2 = GND
PC228_P0_8  Q_CAP  2.2UF 10V 10% X6S  pkg C0402  page 270 : 1 = PVCCIN_CPU0_PVCC ; 2 = GND
PC229_P0_7  Q_CAP  2.2UF 10V 10% X6S  pkg C0402  page 270 : 1 = PVCCIN_CPU0_PVCC ; 2 = GND
PC230_P0_8  Q_CAP  3300PF 50V 10% X7R  pkg 0402  page 270 : 1 = SW_P12V_PVCCIN_CPU0_FLT ; 2 = GND
PC231_P0_7  Q_CAP  3300PF 50V 10% X7R  pkg 0402  page 270 : 1 = SW_P12V_PVCCIN_CPU0_FLT ; 2 = GND
PC232_P0_8  Q_CAP  1UF 16V 10% X6S  pkg C0402  page 270 : 1 = SW_P12V_PVCCIN_CPU0_FLT ; 2 = GND
PC233_P0_7  Q_CAP  1UF 16V 10% X6S  pkg C0402  page 270 : 1 = SW_P12V_PVCCIN_CPU0_FLT ; 2 = GND
PC234  Q_CAP  100NF 50V 10% X7R  pkg C0402  page 270 : 1 = SW_PVCCIN_CPU0_BOOT8_R ; 2 = SW_PVCCIN_CPU0_BOOTR8
PC235  Q_CAP  100NF 50V 10% X7R  pkg C0402  page 270 : 1 = SW_PVCCIN_CPU0_BOOT7_R ; 2 = SW_PVCCIN_CPU0_BOOTR7
PC236_P0_8  Q_CAP  22UF 16V 20% X6S  pkg C0805  page 270 : 1 = SW_P12V_PVCCIN_CPU0_FLT ; 2 = GND
PC237  Q_CAP  680PF 50V 10% X7R  pkg 0402  page 282 : 1 = PVNN_MAIN_CPU0_FB ; 2 = PVNN_MAIN_CPU0_FB_RC
PC237_P0_7  Q_CAP  22UF 16V 20% X6S  pkg C0805  page 270 : 1 = SW_P12V_PVCCIN_CPU0_FLT ; 2 = GND
PC238  Q_CAP  680PF 50V 10% X7R  pkg 0402  page 300 : 1 = PVNN_MAIN_CPU1_FB ; 2 = PVNN_MAIN_CPU1_FB_RC
PC238_P0_8  Q_CAP  22UF 16V 20% X6S  pkg C0805  page 270 : 1 = SW_P12V_PVCCIN_CPU0_FLT ; 2 = GND
PC239_P0_7  Q_CAP  22UF 16V 20% X6S  pkg C0805  page 270 : 1 = SW_P12V_PVCCIN_CPU0_FLT ; 2 = GND
PC240_P0_8  Q_CAP  22UF 16V 20% X6S  pkg C0805  page 270 : 1 = SW_P12V_PVCCIN_CPU0_FLT ; 2 = GND
PC241_P0_7  Q_CAP  22UF 16V 20% X6S  pkg C0805  page 270 : 1 = SW_P12V_PVCCIN_CPU0_FLT ; 2 = GND
PC242_P0_8  Q_CAP  1UF 16V 10% X6S  pkg C0402  page 270 : 1 = PVCCIN_CPU0 ; 2 = GND
PC243_P0_7  Q_CAP  1UF 16V 10% X6S  pkg C0402  page 270 : 1 = PVCCIN_CPU0 ; 2 = GND
PC244_P0_8  Q_CAP  22UF 4V 20% X6S  pkg C0805  page 270 : 1 = PVCCIN_CPU0 ; 2 = GND
PC245_P0_7  Q_CAP  22UF 4V 20% X6S  pkg C0805  page 270 : 1 = PVCCIN_CPU0 ; 2 = GND
PC246_P0_8  Q_CAP  22UF 4V 20% X6S  pkg C0805  page 270 : 1 = PVCCIN_CPU0 ; 2 = GND
PC247_P0_7  Q_CAP  22UF 4V 20% X6S  pkg C0805  page 270 : 1 = PVCCIN_CPU0 ; 2 = GND
PC248  Q_CAP  2.2UF 10V 10% X6S  pkg C0402  page 269 : 1 = PVCCIN_CPU0_VDD6 ; 2 = GND
PC249  Q_CAP  2.2UF 10V 10% X6S  pkg C0402  page 269 : 1 = PVCCIN_CPU0_VDD5 ; 2 = GND
PC250_P0_6  Q_CAP  2.2UF 10V 10% X6S  pkg C0402  page 269 : 1 = PVCCIN_CPU0_PVCC ; 2 = GND
PC251_P0_5  Q_CAP  2.2UF 10V 10% X6S  pkg C0402  page 269 : 1 = PVCCIN_CPU0_PVCC ; 2 = GND
PC252_P0_6  Q_CAP  3300PF 50V 10% X7R  pkg 0402  page 269 : 1 = SW_P12V_PVCCIN_CPU0_FLT ; 2 = GND
PC253_P0_5  Q_CAP  3300PF 50V 10% X7R  pkg 0402  page 269 : 1 = SW_P12V_PVCCIN_CPU0_FLT ; 2 = GND
PC254_P0_6  Q_CAP  1UF 16V 10% X6S  pkg C0402  page 269 : 1 = SW_P12V_PVCCIN_CPU0_FLT ; 2 = GND
PC255_P0_5  Q_CAP  1UF 16V 10% X6S  pkg C0402  page 269 : 1 = SW_P12V_PVCCIN_CPU0_FLT ; 2 = GND
PC256  Q_CAP  100NF 50V 10% X7R  pkg C0402  page 269 : 1 = SW_PVCCIN_CPU0_BOOT6_R ; 2 = SW_PVCCIN_CPU0_BOOTR6
PC257  Q_CAP  100NF 50V 10% X7R  pkg C0402  page 269 : 1 = SW_PVCCIN_CPU0_BOOT5_R ; 2 = SW_PVCCIN_CPU0_BOOTR5
PC258_P0_6  Q_CAP  22UF 16V 20% X6S  pkg C0805  page 269 : 1 = SW_P12V_PVCCIN_CPU0_FLT ; 2 = GND
PC259_P0_5  Q_CAP  22UF 16V 20% X6S  pkg C0805  page 269 : 1 = SW_P12V_PVCCIN_CPU0_FLT ; 2 = GND
PC260_P0_6  Q_CAP  22UF 16V 20% X6S  pkg C0805  page 269 : 1 = SW_P12V_PVCCIN_CPU0_FLT ; 2 = GND
PC261_P0_5  Q_CAP  22UF 16V 20% X6S  pkg C0805  page 269 : 1 = SW_P12V_PVCCIN_CPU0_FLT ; 2 = GND
PC262_P0_6  Q_CAP  22UF 16V 20% X6S  pkg C0805  page 269 : 1 = SW_P12V_PVCCIN_CPU0_FLT ; 2 = GND
PC263_P0_5  Q_CAP  22UF 16V 20% X6S  pkg C0805  page 269 : 1 = SW_P12V_PVCCIN_CPU0_FLT ; 2 = GND
PC266_P0_6  Q_CAP  22UF 4V 20% X6S  pkg C0805  page 269 : 1 = PVCCIN_CPU0 ; 2 = GND
PC267_P0_5  Q_CAP  22UF 4V 20% X6S  pkg C0805  page 269 : 1 = PVCCIN_CPU0 ; 2 = GND
PC268_P0_6  Q_CAP  22UF 4V 20% X6S  pkg C0805  page 269 : 1 = PVCCIN_CPU0 ; 2 = GND
PC269_P0_5  Q_CAP  22UF 4V 20% X6S  pkg C0805  page 269 : 1 = PVCCIN_CPU0 ; 2 = GND
PC270  Q_CAP  2.2UF 10V 10% X6S  pkg C0402  page 268 : 1 = PVCCIN_CPU0_VDD4 ; 2 = GND
PC271  Q_CAP  2.2UF 10V 10% X6S  pkg C0402  page 268 : 1 = PVCCIN_CPU0_VDD3 ; 2 = GND
PC272_P0_4  Q_CAP  2.2UF 10V 10% X6S  pkg C0402  page 268 : 1 = PVCCIN_CPU0_PVCC ; 2 = GND
PC273_P0_3  Q_CAP  2.2UF 10V 10% X6S  pkg C0402  page 268 : 1 = PVCCIN_CPU0_PVCC ; 2 = GND
PC274_P0_4  Q_CAP  3300PF 50V 10% X7R  pkg 0402  page 268 : 1 = SW_P12V_PVCCIN_CPU0_FLT ; 2 = GND
PC275_P0_3  Q_CAP  3300PF 50V 10% X7R  pkg 0402  page 268 : 1 = SW_P12V_PVCCIN_CPU0_FLT ; 2 = GND
PC276_P0_4  Q_CAP  1UF 16V 10% X6S  pkg C0402  page 268 : 1 = SW_P12V_PVCCIN_CPU0_FLT ; 2 = GND
PC277_P0_3  Q_CAP  1UF 16V 10% X6S  pkg C0402  page 268 : 1 = SW_P12V_PVCCIN_CPU0_FLT ; 2 = GND
PC278  Q_CAP  100NF 50V 10% X7R  pkg C0402  page 268 : 1 = SW_PVCCIN_CPU0_BOOT4_R ; 2 = SW_PVCCIN_CPU0_BOOTR4
PC279  Q_CAP  100NF 50V 10% X7R  pkg C0402  page 268 : 1 = SW_PVCCIN_CPU0_BOOT3_R ; 2 = SW_PVCCIN_CPU0_BOOTR3
PC280_P0_4  Q_CAP  22UF 16V 20% X6S  pkg C0805  page 268 : 1 = SW_P12V_PVCCIN_CPU0_FLT ; 2 = GND
PC281_P0_3  Q_CAP  22UF 16V 20% X6S  pkg C0805  page 268 : 1 = SW_P12V_PVCCIN_CPU0_FLT ; 2 = GND
PC282_P0_4  Q_CAP  22UF 16V 20% X6S  pkg C0805  page 268 : 1 = SW_P12V_PVCCIN_CPU0_FLT ; 2 = GND
PC283_P0_3  Q_CAP  22UF 16V 20% X6S  pkg C0805  page 268 : 1 = SW_P12V_PVCCIN_CPU0_FLT ; 2 = GND
PC284_P0_4  Q_CAP  22UF 16V 20% X6S  pkg C0805  page 268 : 1 = SW_P12V_PVCCIN_CPU0_FLT ; 2 = GND
PC285_P0_3  Q_CAP  22UF 16V 20% X6S  pkg C0805  page 268 : 1 = SW_P12V_PVCCIN_CPU0_FLT ; 2 = GND
PC288_P0_4  Q_CAP  22UF 4V 20% X6S  pkg C0805  page 268 : 1 = PVCCIN_CPU0 ; 2 = GND
PC289_P0_3  Q_CAP  22UF 4V 20% X6S  pkg C0805  page 268 : 1 = PVCCIN_CPU0 ; 2 = GND
PC290_P0_4  Q_CAP  22UF 4V 20% X6S  pkg C0805  page 268 : 1 = PVCCIN_CPU0 ; 2 = GND
PC291_P0_3  Q_CAP  22UF 4V 20% X6S  pkg C0805  page 268 : 1 = PVCCIN_CPU0 ; 2 = GND
PC292  Q_CAP  2.2UF 10V 10% X6S  pkg C0402  page 267 : 1 = PVCCIN_CPU0_VDD2 ; 2 = GND
PC293  Q_CAP  2.2UF 10V 10% X6S  pkg C0402  page 267 : 1 = PVCCIN_CPU0_VDD1 ; 2 = GND
PC294_P0_2  Q_CAP  2.2UF 10V 10% X6S  pkg C0402  page 267 : 1 = PVCCIN_CPU0_PVCC ; 2 = GND
PC295_P0_1  Q_CAP  2.2UF 10V 10% X6S  pkg C0402  page 267 : 1 = PVCCIN_CPU0_PVCC ; 2 = GND
PC296_P0_2  Q_CAP  3300PF 50V 10% X7R  pkg 0402  page 267 : 1 = SW_P12V_PVCCIN_CPU0_FLT ; 2 = GND
PC297_P0_1  Q_CAP  3300PF 50V 10% X7R  pkg 0402  page 267 : 1 = SW_P12V_PVCCIN_CPU0_FLT ; 2 = GND
PC298_P0_2  Q_CAP  1UF 16V 10% X6S  pkg C0402  page 267 : 1 = SW_P12V_PVCCIN_CPU0_FLT ; 2 = GND
PC299_P0_1  Q_CAP  1UF 16V 10% X6S  pkg C0402  page 267 : 1 = SW_P12V_PVCCIN_CPU0_FLT ; 2 = GND
PC300  Q_CAP  100NF 50V 10% X7R  pkg C0402  page 267 : 1 = SW_PVCCIN_CPU0_BOOT2_R ; 2 = SW_PVCCIN_CPU0_BOOTR2
PC301  Q_CAP  100NF 50V 10% X7R  pkg C0402  page 267 : 1 = SW_PVCCIN_CPU0_BOOT1_R ; 2 = SW_PVCCIN_CPU0_BOOTR1
PC302_P0_2  Q_CAP  22UF 16V 20% X6S  pkg C0805  page 267 : 1 = SW_P12V_PVCCIN_CPU0_FLT ; 2 = GND
PC303_P0_1  Q_CAP  22UF 16V 20% X6S  pkg C0805  page 267 : 1 = SW_P12V_PVCCIN_CPU0_FLT ; 2 = GND
PC304_P0_2  Q_CAP  22UF 16V 20% X6S  pkg C0805  page 267 : 1 = SW_P12V_PVCCIN_CPU0_FLT ; 2 = GND
PC305_P0_1  Q_CAP  22UF 16V 20% X6S  pkg C0805  page 267 : 1 = SW_P12V_PVCCIN_CPU0_FLT ; 2 = GND
PC306_P0_2  Q_CAP  22UF 16V 20% X6S  pkg C0805  page 267 : 1 = SW_P12V_PVCCIN_CPU0_FLT ; 2 = GND
PC307_P0_1  Q_CAP  22UF 16V 20% X6S  pkg C0805  page 267 : 1 = SW_P12V_PVCCIN_CPU0_FLT ; 2 = GND
PC308_P0_1  Q_CAP  100NF 50V 10% X7R  pkg C0402  page 267 : 1 = PVCCIN_CPU0 ; 2 = GND
PC310_P0_1  Q_CAP  1UF 16V 10% X6S  pkg C0402  page 267 : 1 = PVCCIN_CPU0 ; 2 = GND
PC311_P0_2  Q_CAP  22UF 4V 20% X6S  pkg C0805  page 267 : 1 = PVCCIN_CPU0 ; 2 = GND
PC312_P0_1  Q_CAP  22UF 4V 20% X6S  pkg C0805  page 267 : 1 = PVCCIN_CPU0 ; 2 = GND
PC313_P0_2  Q_CAP  22UF 4V 20% X6S  pkg C0805  page 267 : 1 = PVCCIN_CPU0 ; 2 = GND
PC314_P0_1  Q_CAP  22UF 4V 20% X6S  pkg C0805  page 267 : 1 = PVCCIN_CPU0 ; 2 = GND
PC315  Q_CAPP  270UF 16V 20% OSCON  pkg THLF  page 267 : 1 = SW_P12V_PVCCIN_CPU0_FLT ; 2 = GND
PC316  Q_CAPP  560UF 2.5V 20% OSCON  pkg THLF  page 267 : 1 = PVCCIN_CPU0 ; 2 = GND
PC318  Q_CAPP  270UF 16V 20% OSCON  pkg THLF  page 267 : 1 = SW_P12V_PVCCIN_CPU0_FLT ; 2 = GND
PC319  Q_CAPP  560UF 2.5V 20% OSCON  pkg THLF  page 267 : 1 = PVCCIN_CPU0 ; 2 = GND
PC321  Q_CAPP  270UF 16V 20% OSCON  pkg THLF  page 267 : 1 = SW_P12V_PVCCIN_CPU0_FLT ; 2 = GND
PC322  Q_CAPP  560UF 2.5V 20% OSCON  pkg THLF  page 267 : 1 = PVCCIN_CPU0 ; 2 = GND
PC323  Q_CAPP  330UF 2.5V +10/-35% EMPTY  pkg SMLF  page 267 : 1 = PVCCIN_CPU0 ; 2 = GND
PC324  Q_CAPP  270UF 16V 20% OSCON  pkg THLF  page 267 : 1 = SW_P12V_PVCCIN_CPU0_FLT ; 2 = GND
PC325  Q_CAPP  560UF 2.5V 20% OSCON  pkg THLF  page 267 : 1 = PVCCIN_CPU0 ; 2 = GND
PC326  Q_CAPP  330UF 2.5V +10/-35% EMPTY  pkg SMLF  page 267 : 1 = PVCCIN_CPU0 ; 2 = GND
PC329  Q_CAP  0.1UF 25V 10% EMPTY  pkg 0402  page 266 : 1 = PVCCIN_CPU0_CSPIN ; 2 = GND
PC330  Q_CAP  0.1UF 25V 10% X7R  pkg 0402  page 266 : 1 = PVCCIN_CPU0_VIN_CSNIN ; 2 = GND
PC331  Q_CAP  3300PF 50V 10% X7R  pkg 0402  page 266 : 1 = SH_PVCCIN_CPU0_R ; 2 = VSENSE_PVCCIN_CPU0_DN
PC334  Q_CAP  0.1UF 25V 10% EMPTY  pkg 0402  page 266 : 1 = PVCCIN_CPU0_VCC ; 2 = GND
PC335  Q_CAP  10UF 6.3V 20% X6S  pkg C0402  page 266 : 1 = PVCCIN_CPU0_VREF ; 2 = GND
PC336  Q_CAP  470PF 50V 10% X7R  pkg 0402  page 266 : 1 = PVCCIN_CPU0_ATSEN ; 2 = GND
PC337  Q_CAP  1UF 16V 10% X6S  pkg C0402  page 266 : 1 = PVCCIN_CPU0_VCC ; 2 = GND
PC373  Q_CAP  2.2UF 10V 10% X6S  pkg C0402  page 297 : 1 = PVCCD_HV_CPU1_VDD1 ; 2 = GND
PC374  Q_CAP  3300PF 50V 10% X7R  pkg 0402  page 297 : 1 = SW_P12V_PVCCINFAON_CPU1_FLT ; 2 = GND
PC375  Q_CAP  1UF 16V 10% X6S  pkg C0402  page 297 : 1 = SW_P12V_PVCCINFAON_CPU1_FLT ; 2 = GND
PC376  Q_CAP  100NF 50V 10% X7R  pkg C0402  page 297 : 1 = SW_PVCCD_HV_CPU1_BOOT1_R ; 2 = SW_PVCCD_HV_CPU1_BOOTR1
PC377  Q_CAP  22UF 16V 20% X6S  pkg C0805  page 297 : 1 = SW_P12V_PVCCINFAON_CPU1_FLT ; 2 = GND
PC378  Q_CAP  22UF 16V 20% X6S  pkg C0805  page 297 : 1 = SW_P12V_PVCCINFAON_CPU1_FLT ; 2 = GND
PC379  Q_CAP  100NF 50V 10% X7R  pkg C0402  page 297 : 1 = PVCCD_HV_CPU1 ; 2 = GND
PC381  Q_CAP  22UF 4V 20% X6S  pkg C0805  page 297 : 1 = PVCCD_HV_CPU1 ; 2 = GND
PC382  Q_CAP  22UF 4V 20% X6S  pkg C0805  page 297 : 1 = PVCCD_HV_CPU1 ; 2 = GND
PC384  Q_CAPP  560UF 2.5V 20% OSCON  pkg THLF  page 297 : 1 = PVCCD_HV_CPU1 ; 2 = GND
PC385  Q_CAPP  560UF 2.5V 20% OSCON  pkg THLF  page 297 : 1 = PVCCD_HV_CPU1 ; 2 = GND
PC386  Q_CAP  0.1UF 25V 10% X7R  pkg 0402  page 296 : 1 = PVCCD_HV_CPU1_ISENSE_P ; 2 = GND
PC389  Q_CAP  3300PF 50V 10% X7R  pkg 0402  page 296 : 1 = SH_PVCCD_HV_CPU1_R ; 2 = VSENSE_PVCCD_HV_CPU1_DN
PC390  Q_CAP  0.1UF 25V 10% X7R  pkg 0402  page 296 : 1 = PVCCD_HV_CPU1_ISENSE_N ; 2 = GND
PC391  Q_CAP  100NF 50V 10% EMPTY  pkg C0402  page 296 : 1 = PVCCD_HV_CPU1_VCC ; 2 = GND
PC392  Q_CAP  10UF 6.3V 20% X6S  pkg C0402  page 296 : 1 = PVCCD_HV_CPU1_VREF ; 2 = GND
PC393  Q_CAP  470PF 50V 10% X7R  pkg 0402  page 296 : 1 = PVCCD_HV_CPU1_ATSEN ; 2 = GND
PC394  Q_CAP  1UF 16V 10% X6S  pkg C0402  page 296 : 1 = PVCCD_HV_CPU1_VCC ; 2 = GND
PC395  Q_CAP  2.2UF 10V 10% X6S  pkg C0402  page 289 : 1 = PVCCFA_EHV_FIVRA_CPU1_VDD1 ; 2 = GND
PC396  Q_CAP  2.2UF 10V 10% X6S  pkg C0402  page 289 : 1 = PVCCFA_EHV_FIVRA_CPU1_VDD2 ; 2 = GND
PC397_P1_1  Q_CAP  3300PF 50V 10% X7R  pkg 0402  page 289 : 1 = SW_P12V_PVCCFA_EHV_FIVRA_CPU1_R ; 2 = GND
PC398_P1_2  Q_CAP  3300PF 50V 10% X7R  pkg 0402  page 289 : 1 = SW_P12V_PVCCFA_EHV_FIVRA_CPU1_L ; 2 = GND
PC399_P1_1  Q_CAP  1UF 16V 10% X6S  pkg C0402  page 289 : 1 = SW_P12V_PVCCFA_EHV_FIVRA_CPU1_R ; 2 = GND
PC400_P1_2  Q_CAP  1UF 16V 10% X6S  pkg C0402  page 289 : 1 = SW_P12V_PVCCFA_EHV_FIVRA_CPU1_L ; 2 = GND
PC401  Q_CAP  100NF 50V 10% X7R  pkg C0402  page 289 : 1 = SW_PVCCFA_EHV_FIVRA_CPU1_BOOT1_ ; 2 = SW_PVCCFA_EHV_FIVRA_CPU1_BOOTR1
PC402  Q_CAP  100NF 50V 10% X7R  pkg C0402  page 289 : 1 = SW_PVCCFA_EHV_FIVRA_CPU1_BOOT2_ ; 2 = SW_PVCCFA_EHV_FIVRA_CPU1_BOOTR2
PC403_P1_1  Q_CAP  22UF 16V 20% X6S  pkg C0805  page 289 : 1 = SW_P12V_PVCCFA_EHV_FIVRA_CPU1_R ; 2 = GND
PC404_P1_2  Q_CAP  22UF 16V 20% X6S  pkg C0805  page 289 : 1 = SW_P12V_PVCCFA_EHV_FIVRA_CPU1_L ; 2 = GND
PC405_P1_1  Q_CAP  22UF 16V 20% X6S  pkg C0805  page 289 : 1 = SW_P12V_PVCCFA_EHV_FIVRA_CPU1_R ; 2 = GND
PC406_P1_2  Q_CAP  22UF 16V 20% X6S  pkg C0805  page 289 : 1 = SW_P12V_PVCCFA_EHV_FIVRA_CPU1_L ; 2 = GND
PC408_P1_2  Q_CAP  1UF 16V 10% X6S  pkg C0402  page 289 : 1 = PVCCFA_EHV_FIVRA_CPU1 ; 2 = GND
PC410_P1_1  Q_CAP  22UF 4V 20% X6S  pkg C0805  page 289 : 1 = PVCCFA_EHV_FIVRA_CPU1 ; 2 = GND
PC411_P1_2  Q_CAP  22UF 4V 20% X6S  pkg C0805  page 289 : 1 = PVCCFA_EHV_FIVRA_CPU1 ; 2 = GND
